FILE_TYPE = CONNECTIVITY;
{Allegro Design Entry HDL 16.6-p007 (v16-6-112F) 10/10/2012}
"PAGE_NUMBER" = 225;
0"NC";
1"GND\g";
2"PVDDQ_GHJ\g";
3"GND\g";
4"VR_FET_SW_P12V_STBY_PVDDQ_GHJ\g";
5"GND\g";
6"P12V_STBY\g";
7"GND\g";
8"PVDDQ_GHJ\g";
9"PVDDQ_GHJ\g";
10"GND\g";
11"PVDDQ_GHJ\g";
12"PVDDQ_GHJ\g";
13"GND\g";
14"PVDDQ_GHJ\g";
15"GND\g";
16"PVDDQ_GHJ\g";
17"GND\g";
18"GND\g";
19"PVDDQ_GHJ\g";
20"GND\g";
21"PVDDQ_GHJ\g";
22"GND\g";
23"PVDDQ_GHJ\g";
24"PVDDQ_GHJ\g";
25"GND\g";
26"PVDDQ_GHJ\g";
27"GND\g";
28"VSENSE_PVDDQ_GHJ_P";
29"VSENSE_PVDDQ_GHJ_N";
%"PVDDQ_GHJ"
"1","(2550,2000)","0","mstr_symbols","I109";
;
CDS_LIB"mstr_symbols"
VOLTAGE"1.2V"
BOM_COST"MEM_VRD_PVDDQ_CD"
ROOM"VDDQ_GHJ_PWR_VR"
BODY_TYPE"PLUMBING"
HDL_POWER"PVDDQ_GHJ";
"G\NAC"2;
%"GND"
"1","(4275,1350)","0","mstr_symbols","I114";
;
ROOM"VDDQ_GHJ_PWR_VR"
BOM_COST"MEM_VRD_PVDDQ_CD"
VOLTAGE"0"
CDS_LIB"mstr_symbols"
SIZE"1B"
BODY_TYPE"PLUMBING"
HDL_POWER"GND";
"A\NAC"3;
%"VCC_CORE"
"1","(-1250,1575)","0","mstr_symbols","I120";
;
HDL_POWER"VR_FET_SW_P12V_STBY_PVDDQ_GHJ"
CDS_LIB"mstr_symbols";
"A"4;
%"GND"
"1","(-1250,875)","0","mstr_symbols","I123";
;
CDS_LIB"mstr_symbols"
SIZE"1B"
VOLTAGE"0"
ROOM"VDDQ_GHJ_PWR_VR"
BOM_COST"MEM_VRD_PVDDQ_CD"
BODY_TYPE"PLUMBING"
HDL_POWER"GND";
"A\NAC"5;
%"P12V_STBY"
"1","(-2025,1550)","0","mstr_symbols","I176";
;
VOLTAGE"12.0V"
SIZE"1B"
CDS_LIB"mstr_symbols"
BODY_TYPE"PLUMBING"
HDL_POWER"P12V_STBY";
"G\NAC"6;
%"GND"
"1","(-350,2725)","0","mstr_symbols","I182";
;
SIZE"1B"
CDS_LIB"mstr_symbols"
VOLTAGE"0"
ROOM"VDDQ_ABC_PWR_VR"
BOM_COST"MEM_VRD_PVDDQ_CD"
BODY_TYPE"PLUMBING"
HDL_POWER"GND";
"A\NAC"7;
%"PVDDQ_GHJ"
"1","(-2325,3375)","0","mstr_symbols","I185";
;
BOM_COST"MEM_VRD_PVPP_AB"
ROOM"VDDQ_GHJ_PWR_VR"
CDS_LIB"mstr_symbols"
VOLTAGE"1.2V"
BODY_TYPE"PLUMBING"
HDL_POWER"PVDDQ_GHJ";
"G\NAC"8;
%"PVDDQ_GHJ"
"1","(2600,1250)","0","mstr_symbols","I189";
;
VOLTAGE"1.2V"
CDS_LIB"mstr_symbols"
BOM_COST"MEM_VRD_PVDDQ_CD"
ROOM"VDDQ_GHJ_PWR_VR"
BODY_TYPE"PLUMBING"
HDL_POWER"PVDDQ_GHJ";
"G\NAC"9;
%"GND"
"1","(3425,575)","0","mstr_symbols","I191";
;
ROOM"VDDQ_GHJ_PWR_VR"
BOM_COST"MEM_VRD_PVDDQ_CD"
VOLTAGE"0"
CDS_LIB"mstr_symbols"
SIZE"1B"
BODY_TYPE"PLUMBING"
HDL_POWER"GND";
"A\NAC"10;
%"CAP_A"
"1","(2600,975)","0","dev_discrete","I196";
;
BOM_SS"078.1061T.M001"
GROUP"PWR_MLCC_CAP"
PACK_TYPE"0603V"
MATERIAL"X5R"
VALUE"47UF"
VOLTAGE"4V"
TOLERANCE"20%"
LOCATION"C8T4"
PART_NUMBER"602433-106"
CDS_LIB"dev_discrete"
CDS_LOCATION"C8T4"
CDS_SEC"1"
SEC"1"
SEC_TYPE"0603V";
"B"
$PN"2"10;
"A"
$PN"1"9;
%"CAP_A"
"1","(2950,975)","0","dev_discrete","I197";
;
GROUP"PWR_MLCC_CAP"
BOM_SS"NOPOP"
VALUE"47UF"
VOLTAGE"4V"
MATERIAL"X5R"
PACK_TYPE"0603V"
LOCATION"C2G8"
PART_NUMBER"602433-106"
TOLERANCE"20%"
CDS_LIB"dev_discrete"
CDS_LOCATION"C2G8"
CDS_SEC"1"
SEC_TYPE"0603V"
SEC"1";
"B"
$PN"2"10;
"A"
$PN"1"9;
%"CAP_A"
"1","(3350,975)","0","dev_discrete","I198";
;
GROUP"PWR_MLCC_CAP"
BOM_SS"NOPOP"
PACK_TYPE"0603V"
MATERIAL"X5R"
TOLERANCE"20%"
VALUE"47UF"
VOLTAGE"4V"
LOCATION"C8T2"
PART_NUMBER"602433-106"
CDS_LIB"dev_discrete"
SEC"1"
SEC_TYPE"0603V"
CDS_SEC"1"
CDS_LOCATION"C8T2";
"B"
$PN"2"10;
"A"
$PN"1"9;
%"CAP_A"
"1","(2550,1725)","0","dev_discrete","I199";
;
BOM_SS"NOPOP"
GROUP"PWR_MLCC_CAP"
PART_NUMBER"602433-106"
LOCATION"C8U13"
VALUE"47UF"
VOLTAGE"4V"
MATERIAL"X5R"
TOLERANCE"20%"
PACK_TYPE"0603V"
CDS_LIB"dev_discrete"
CDS_LOCATION"C8U13"
CDS_SEC"1"
SEC_TYPE"0603V"
SEC"1";
"B"
$PN"2"3;
"A"
$PN"1"2;
%"CAP_A"
"1","(2900,1725)","0","dev_discrete","I200";
;
GROUP"PWR_MLCC_CAP"
BOM_SS"NOPOP"
TOLERANCE"20%"
PACK_TYPE"0603V"
VOLTAGE"4V"
LOCATION"C2G15"
VALUE"47UF"
MATERIAL"X5R"
PART_NUMBER"602433-106"
CDS_LIB"dev_discrete"
CDS_LOCATION"C2G15"
CDS_SEC"1"
SEC_TYPE"0603V"
SEC"1";
"B"
$PN"2"3;
"A"
$PN"1"2;
%"CAP_A"
"1","(3300,1725)","0","dev_discrete","I201";
;
BOM_SS"NOPOP"
GROUP"PWR_MLCC_CAP"
PACK_TYPE"0603V"
LOCATION"C2F1"
VALUE"47UF"
TOLERANCE"20%"
VOLTAGE"4V"
MATERIAL"X5R"
PART_NUMBER"602433-106"
CDS_LIB"dev_discrete"
CDS_LOCATION"C2F1"
CDS_SEC"1"
SEC_TYPE"0603V"
SEC"1";
"B"
$PN"2"3;
"A"
$PN"1"2;
%"CAP_A"
"1","(3650,1725)","0","dev_discrete","I202";
;
PART_NUMBER"602433-106"
GROUP"PWR_MLCC_CAP"
BOM_SS"NOPOP"
PACK_TYPE"0603V"
MATERIAL"X5R"
VOLTAGE"4V"
TOLERANCE"20%"
VALUE"47UF"
LOCATION"C8T1"
CDS_LIB"dev_discrete"
SEC"1"
SEC_TYPE"0603V"
CDS_SEC"1"
CDS_LOCATION"C8T1";
"B"
$PN"2"3;
"A"
$PN"1"2;
%"CAP_A"
"1","(4000,1725)","0","dev_discrete","I203";
;
GROUP"PWR_MLCC_CAP"
PACK_TYPE"0603V"
PART_NUMBER"602433-106"
LOCATION"C8U9"
VOLTAGE"4V"
VALUE"47UF"
TOLERANCE"20%"
MATERIAL"X5R"
BOM_SS"NOPOP"
CDS_LIB"dev_discrete"
SEC"1"
SEC_TYPE"0603V"
CDS_SEC"1"
CDS_LOCATION"C8U9";
"B"
$PN"2"3;
"A"
$PN"1"2;
%"CAP_A"
"1","(4400,1725)","0","dev_discrete","I204";
;
GROUP"PWR_MLCC_CAP"
PART_NUMBER"602433-106"
VALUE"47UF"
PACK_TYPE"0603V"
TOLERANCE"20%"
VOLTAGE"4V"
MATERIAL"X5R"
LOCATION"C8T11"
BOM_SS"NOPOP"
CDS_LIB"dev_discrete"
CDS_LOCATION"C8T11"
CDS_SEC"1"
SEC_TYPE"0603V"
SEC"1";
"B"
$PN"2"3;
"A"
$PN"1"2;
%"PVDDQ_GHJ"
"1","(-1450,3375)","0","mstr_symbols","I205";
;
BOM_COST"MEM_VRD_PVPP_AB"
ROOM"VDDQ_GHJ_PWR_VR"
CDS_LIB"mstr_symbols"
VOLTAGE"1.2V"
BODY_TYPE"PLUMBING"
HDL_POWER"PVDDQ_GHJ";
"G\NAC"11;
%"GND"
"1","(-2325,2625)","0","mstr_symbols","I206";
;
BOM_COST"MEM_VRD_PVDDQ_CD"
ROOM"VDDQ_ABC_PWR_VR"
CDS_LIB"mstr_symbols"
VOLTAGE"0"
SIZE"1B"
BODY_TYPE"PLUMBING"
HDL_POWER"GND";
"A\NAC"1;
%"PVDDQ_GHJ"
"1","(-2275,500)","0","mstr_symbols","I222";
;
VOLTAGE"1.2V"
CDS_LIB"mstr_symbols"
BODY_TYPE"PLUMBING"
HDL_POWER"PVDDQ_GHJ";
"G\NAC"12;
%"GND"
"1","(-2275,-75)","0","mstr_symbols","I224";
;
SIZE"1B"
VOLTAGE"0"
CDS_LIB"mstr_symbols"
BOM_COST"PROC_VRD_VCCIN_CPU0"
ROOM"VDDQ_ABC_PWR_VR"
BODY_TYPE"PLUMBING"
HDL_POWER"GND";
"A\NAC"13;
%"PVDDQ_GHJ"
"1","(-2250,-200)","0","mstr_symbols","I240";
;
VOLTAGE"1.2V"
CDS_LIB"mstr_symbols"
BODY_TYPE"PLUMBING"
HDL_POWER"PVDDQ_GHJ";
"G\NAC"14;
%"GND"
"1","(-2250,-800)","0","mstr_symbols","I242";
;
CDS_LIB"mstr_symbols"
VOLTAGE"0"
SIZE"1B"
ROOM"VDDQ_ABC_PWR_VR"
BOM_COST"PROC_VRD_VCCIN_CPU0"
BODY_TYPE"PLUMBING"
HDL_POWER"GND";
"A\NAC"15;
%"SHUNT"
"1","(-250,2325)","0","mstr_misc","I243";
;
CDS_SEC"1"
CDS_LOCATION"SH7U1"
PART_NUMBER"N_A"
LOCATION"SH7U1"
PIN_SHORT"A:B"
PACK_TYPE"SH0201"
MATERIAL"EMPTY"
SEC"1"
SEC_TYPE"SH0201"
CDS_LIB"mstr_misc";
"A"
$PN"1"28;
"B"
$PN"2"23;
%"SHUNT"
"1","(-275,1875)","0","mstr_misc","I244";
;
CDS_SEC"1"
CDS_LOCATION"SH7U2"
PART_NUMBER"N_A"
LOCATION"SH7U2"
MATERIAL"EMPTY"
PACK_TYPE"SH0201"
PIN_SHORT"A:B"
CDS_LIB"mstr_misc"
SEC"1"
SEC_TYPE"SH0201";
"A"
$PN"1"29;
"B"
$PN"2"22;
%"SC22U16V5MX-4-GP"
"1","(-250,1150)","0","w_hdl","I246";
;
CDS_SEC"1"
CDS_LOCATION"C22W1"
RATED"16V"
TOLERANCE"20%"
LOCATION"C22W1"
ATTRIBUTE"22UF"
PACK_SIZE"0805"
TYPE"X6S"
VALUE"SC22U16V5MX-4-GP"
CDS_LMAN_SYM_OUTLINE"-50,25,50,-25"
CDS_LIB"w_hdl"
PART_NUMBER"078.22611.0811"
SEC_TYPE"SMD-BCG5"
SEC"1"
PACK_TYPE"SMD-BCG5";
"2"
$PN"2"5;
"1"
$PN"1"4;
%"SC22U16V5MX-4-GP"
"1","(-950,1150)","0","w_hdl","I247";
;
CDS_SEC"1"
CDS_LOCATION"C22W2"
VALUE"SC22U16V5MX-4-GP"
TOLERANCE"20%"
RATED"16V"
ATTRIBUTE"22UF"
PACK_SIZE"0805"
TYPE"X6S"
LOCATION"C22W2"
PACK_TYPE"SMD-BCG5"
SEC"1"
SEC_TYPE"SMD-BCG5"
PART_NUMBER"078.22611.0811"
CDS_LIB"w_hdl"
CDS_LMAN_SYM_OUTLINE"-50,25,50,-25";
"2"
$PN"2"5;
"1"
$PN"1"4;
%"SC22U16V5MX-4-GP"
"1","(450,1150)","0","w_hdl","I249";
;
CDS_SEC"1"
CDS_LOCATION"C22W3"
VALUE"SC22U16V5MX-4-GP"
RATED"16V"
TOLERANCE"20%"
PACK_SIZE"0805"
TYPE"X6S"
LOCATION"C22W3"
ATTRIBUTE"22UF"
CDS_LMAN_SYM_OUTLINE"-50,25,50,-25"
CDS_LIB"w_hdl"
PART_NUMBER"078.22611.0811"
SEC_TYPE"SMD-BCG5"
SEC"1"
PACK_TYPE"SMD-BCG5";
"2"
$PN"2"5;
"1"
$PN"1"4;
%"SC22U16V5MX-4-GP"
"1","(150,1150)","0","w_hdl","I250";
;
CDS_SEC"1"
CDS_LOCATION"C1G2"
RATED"16V"
TYPE"X6S"
ATTRIBUTE"22UF"
TOLERANCE"20%"
LOCATION"C1G2"
PACK_SIZE"0805"
VALUE"SC22U16V5MX-4-GP"
PACK_TYPE"SMD-BCG5"
SEC"1"
SEC_TYPE"SMD-BCG5"
PART_NUMBER"078.22611.0811"
CDS_LIB"w_hdl"
CDS_LMAN_SYM_OUTLINE"-50,25,50,-25";
"2"
$PN"2"5;
"1"
$PN"1"4;
%"SC22U16V5MX-4-GP"
"1","(1150,1150)","0","w_hdl","I251";
;
CDS_SEC"1"
CDS_LOCATION"C22W4"
PACK_SIZE"0805"
TYPE"X6S"
TOLERANCE"20%"
RATED"16V"
ATTRIBUTE"22UF"
LOCATION"C22W4"
VALUE"SC22U16V5MX-4-GP"
PACK_TYPE"SMD-BCG5"
SEC"1"
SEC_TYPE"SMD-BCG5"
PART_NUMBER"078.22611.0811"
CDS_LIB"w_hdl"
CDS_LMAN_SYM_OUTLINE"-50,25,50,-25";
"2"
$PN"2"5;
"1"
$PN"1"4;
%"IND-100NH-35-GP"
"1","(-1750,1375)","1","w_hdl","I253";
;
CDS_SEC"1"
CDS_LOCATION"L1F1"
PACK_SIZE"DCR=0.16MOHM"
RATED"ISAT=16A@25C"
ATTRIBUTE"100NH"
VALUE"IND-100NH-35-GP"
LOCATION"L1F1"
TYPE"IRMS=29A@DELTA_T<45C"
CDS_LMAN_SYM_OUTLINE"-75,100,75,-100"
CDS_LIB"w_hdl"
PART_NUMBER"068.1011N.M001"
SEC_TYPE"DISCRET-G8"
SEC"1"
PACK_TYPE"DISCRET-G8";
"F"
$PN"2"4;
"S"
$PN"1"6;
%"PVDDQ_GHJ"
"1","(100,3350)","0","mstr_symbols","I257";
;
BOM_COST"MEM_VRD_PVPP_AB"
ROOM"VDDQ_GHJ_PWR_VR"
CDS_LIB"mstr_symbols"
VOLTAGE"1.2V"
BODY_TYPE"PLUMBING"
HDL_POWER"PVDDQ_GHJ";
"G\NAC"16;
%"GND"
"1","(100,2575)","0","mstr_symbols","I258";
;
ROOM"PVCCIN_CPU1_DECAP_VR"
CDS_LIB"mstr_symbols"
SIZE"1B"
VOLTAGE"0"
BODY_TYPE"PLUMBING"
HDL_POWER"GND";
"A\NAC"17;
%"CAP_A"
"1","(700,2100)","0","dev_discrete","I261";
;
PACK_TYPE"0603V"
TOLERANCE"20%"
VOLTAGE"4V"
MATERIAL"X6S"
VALUE"22.0UF"
LOCATION"C2D45"
PART_NUMBER"E15431-004"
GROUP"PWR_MLCC_CAP"
CDS_LOCATION"C2D45"
BOM_COST"PROC"
CDS_LIB"dev_discrete"
CDS_SEC"1"
$SEC"1"
ROOM"PVCCIN_CPU1_DECAP_VR";
"B"
$PN"2"18;
"A"
$PN"1"19;
%"CAP_A"
"1","(1600,2100)","0","dev_discrete","I262";
;
CDS_SEC"1"
TOLERANCE"20%"
VALUE"22.0UF"
LOCATION"C3D25"
VOLTAGE"4V"
PACK_TYPE"0603V"
MATERIAL"X6S"
GROUP"PWR_MLCC_CAP"
PART_NUMBER"E15431-004"
ROOM"PVCCIN_CPU1_DECAP_VR"
CDS_LIB"dev_discrete"
BOM_COST"PROC"
CDS_LOCATION"C3D25"
SEC_TYPE"0603V"
SEC"1";
"B"
$PN"2"18;
"A"
$PN"1"19;
%"CAP_A"
"1","(1300,2100)","0","dev_discrete","I263";
;
CDS_SEC"1"
LOCATION"C2D47"
TOLERANCE"20%"
PACK_TYPE"0603V"
VALUE"22.0UF"
VOLTAGE"4V"
MATERIAL"X6S"
GROUP"PWR_MLCC_CAP"
PART_NUMBER"E15431-004"
ROOM"PVCCIN_CPU1_DECAP_VR"
CDS_LIB"dev_discrete"
BOM_COST"PROC"
CDS_LOCATION"C2D47"
SEC_TYPE"0603V"
SEC"1";
"B"
$PN"2"18;
"A"
$PN"1"19;
%"CAP_A"
"1","(1000,2100)","0","dev_discrete","I264";
;
CDS_SEC"1"
GROUP"PWR_MLCC_CAP"
VALUE"22.0UF"
LOCATION"C2D46"
PART_NUMBER"E15431-004"
PACK_TYPE"0603V"
MATERIAL"X6S"
TOLERANCE"20%"
VOLTAGE"4V"
ROOM"PVCCIN_CPU1_DECAP_VR"
CDS_LIB"dev_discrete"
BOM_COST"PROC"
CDS_LOCATION"C2D46"
SEC_TYPE"0603V"
SEC"1";
"B"
$PN"2"18;
"A"
$PN"1"19;
%"GND"
"1","(1600,1750)","0","mstr_symbols","I265";
;
VOLTAGE"0"
SIZE"1B"
CDS_LIB"mstr_symbols"
ROOM"PVCCIN_CPU1_DECAP_VR"
BODY_TYPE"PLUMBING"
HDL_POWER"GND";
"A\NAC"18;
%"PVDDQ_GHJ"
"1","(700,2350)","0","mstr_symbols","I266";
;
VOLTAGE"1.2V"
CDS_LIB"mstr_symbols"
ROOM"VDDQ_GHJ_PWR_VR"
BOM_COST"MEM_VRD_PVPP_AB"
BODY_TYPE"PLUMBING"
HDL_POWER"PVDDQ_GHJ";
"G\NAC"19;
%"GND"
"1","(1625,2850)","0","mstr_symbols","I267";
;
VOLTAGE"0"
SIZE"1B"
CDS_LIB"mstr_symbols"
ROOM"PVCCIN_CPU1_DECAP_VR"
BODY_TYPE"PLUMBING"
HDL_POWER"GND";
"A\NAC"20;
%"PVDDQ_GHJ"
"1","(1625,3275)","0","mstr_symbols","I269";
;
VOLTAGE"1.2V"
CDS_LIB"mstr_symbols"
ROOM"VDDQ_GHJ_PWR_VR"
BOM_COST"MEM_VRD_PVPP_AB"
BODY_TYPE"PLUMBING"
HDL_POWER"PVDDQ_GHJ";
"G\NAC"21;
%"CAP_A"
"1","(-1450,3100)","0","dev_discrete","I270";
;
PACK_TYPE"0603V"
VALUE"22.0UF"
VOLTAGE"4V"
TOLERANCE"20%"
LOCATION"C2D43"
MATERIAL"X6S"
PART_NUMBER"E15431-004"
GROUP"PWR_MLCC_CAP"
BOM_COST"PROC_SOCKET"
CDS_LIB"dev_discrete"
CDS_SEC"1"
$SEC"1"
ROOM"PVCCIN_CPU0_DECAP_VR"
CDS_LOCATION"C2D43";
"B"
$PN"2"7;
"A"
$PN"1"11;
%"CAP_A"
"1","(-1100,3100)","0","dev_discrete","I271";
;
TOLERANCE"20%"
VOLTAGE"4V"
VALUE"22.0UF"
LOCATION"C2D41"
PACK_TYPE"0603V"
MATERIAL"X6S"
GROUP"PWR_MLCC_CAP"
PART_NUMBER"E15431-004"
BOM_COST"PROC_SOCKET"
CDS_LIB"dev_discrete"
CDS_SEC"1"
$SEC"1"
ROOM"PVCCIN_CPU0_DECAP_VR"
CDS_LOCATION"C2D41";
"B"
$PN"2"7;
"A"
$PN"1"11;
%"CAP_A"
"1","(-750,3100)","0","dev_discrete","I272";
;
VOLTAGE"4V"
LOCATION"C2D44"
MATERIAL"X6S"
PART_NUMBER"E15431-004"
PACK_TYPE"0603V"
GROUP"PWR_MLCC_CAP"
TOLERANCE"20%"
VALUE"22.0UF"
BOM_COST"PROC_SOCKET"
CDS_LIB"dev_discrete"
CDS_SEC"1"
$SEC"1"
ROOM"PVCCIN_CPU0_DECAP_VR"
CDS_LOCATION"C2D44";
"B"
$PN"2"7;
"A"
$PN"1"11;
%"CAP_A"
"1","(-350,3100)","0","dev_discrete","I273";
;
PACK_TYPE"0603V"
GROUP"PWR_MLCC_CAP"
LOCATION"C2D42"
MATERIAL"X6S"
VALUE"22.0UF"
PART_NUMBER"E15431-004"
VOLTAGE"4V"
TOLERANCE"20%"
BOM_COST"PROC_SOCKET"
CDS_LIB"dev_discrete"
CDS_SEC"1"
$SEC"1"
ROOM"PVCCIN_CPU0_DECAP_VR"
CDS_LOCATION"C2D42";
"B"
$PN"2"7;
"A"
$PN"1"11;
%"CAP_A"
"1","(-2275,250)","0","dev_discrete","I274";
;
LOCATION"C2G10"
TOLERANCE"20%"
MATERIAL"X5R"
VALUE"47UF"
VOLTAGE"4V"
PACK_TYPE"0603V"
PART_NUMBER"602433-106"
GROUP"PWR_MLCC_CAP"
BOM_SS"E15431-004"
CDS_LIB"dev_discrete"
SEC"1"
SEC_TYPE"0603V"
CDS_SEC"1"
CDS_LOCATION"C2G10";
"B"
$PN"2"13;
"A"
$PN"1"12;
%"CAP_A"
"1","(-1975,250)","0","dev_discrete","I275";
;
GROUP"PWR_MLCC_CAP"
PACK_TYPE"0603V"
PART_NUMBER"602433-106"
MATERIAL"X5R"
TOLERANCE"20%"
VOLTAGE"4V"
VALUE"47UF"
LOCATION"C2G11"
BOM_SS"E15431-004"
CDS_SEC"1"
SEC_TYPE"0603V"
SEC"1"
CDS_LIB"dev_discrete"
CDS_LOCATION"C2G11";
"B"
$PN"2"13;
"A"
$PN"1"12;
%"CAP_A"
"1","(-1675,250)","0","dev_discrete","I276";
;
PACK_TYPE"0603V"
LOCATION"C2G12"
TOLERANCE"20%"
MATERIAL"X5R"
VALUE"47UF"
VOLTAGE"4V"
PART_NUMBER"602433-106"
GROUP"PWR_MLCC_CAP"
BOM_SS"E15431-004"
CDS_LIB"dev_discrete"
SEC"1"
SEC_TYPE"0603V"
CDS_SEC"1"
CDS_LOCATION"C2G12";
"B"
$PN"2"13;
"A"
$PN"1"12;
%"CAP_A"
"1","(-1400,250)","0","dev_discrete","I277";
;
VOLTAGE"4V"
GROUP"PWR_MLCC_CAP"
PACK_TYPE"0603V"
PART_NUMBER"602433-106"
MATERIAL"X5R"
LOCATION"C2G1"
VALUE"47UF"
TOLERANCE"20%"
BOM_SS"E15431-004"
CDS_SEC"1"
SEC_TYPE"0603V"
SEC"1"
CDS_LIB"dev_discrete"
CDS_LOCATION"C2G1";
"B"
$PN"2"13;
"A"
$PN"1"12;
%"CAP_A"
"1","(-1125,250)","0","dev_discrete","I278";
;
GROUP"PWR_MLCC_CAP"
VOLTAGE"4V"
MATERIAL"X5R"
TOLERANCE"20%"
PACK_TYPE"0603V"
PART_NUMBER"602433-106"
VALUE"47UF"
LOCATION"C2G9"
BOM_SS"E15431-004"
CDS_SEC"1"
SEC_TYPE"0603V"
SEC"1"
CDS_LIB"dev_discrete"
CDS_LOCATION"C2G9";
"B"
$PN"2"13;
"A"
$PN"1"12;
%"CAP_A"
"1","(-825,250)","0","dev_discrete","I279";
;
GROUP"PWR_MLCC_CAP"
VOLTAGE"4V"
LOCATION"C2G2"
PACK_TYPE"0603V"
PART_NUMBER"602433-106"
MATERIAL"X5R"
TOLERANCE"20%"
VALUE"47UF"
BOM_SS"E15431-004"
CDS_SEC"1"
SEC_TYPE"0603V"
SEC"1"
CDS_LIB"dev_discrete"
CDS_LOCATION"C2G2";
"B"
$PN"2"13;
"A"
$PN"1"12;
%"CAP_A"
"1","(-525,250)","0","dev_discrete","I280";
;
GROUP"PWR_MLCC_CAP"
VOLTAGE"4V"
VALUE"47UF"
TOLERANCE"20%"
LOCATION"C2G3"
MATERIAL"X5R"
PACK_TYPE"0603V"
PART_NUMBER"602433-106"
BOM_SS"E15431-004"
CDS_SEC"1"
SEC_TYPE"0603V"
SEC"1"
CDS_LIB"dev_discrete"
CDS_LOCATION"C2G3";
"B"
$PN"2"13;
"A"
$PN"1"12;
%"CAP_A"
"1","(-250,250)","0","dev_discrete","I281";
;
GROUP"PWR_MLCC_CAP"
VOLTAGE"4V"
VALUE"47UF"
MATERIAL"X5R"
TOLERANCE"20%"
LOCATION"C2G4"
PACK_TYPE"0603V"
PART_NUMBER"602433-106"
BOM_SS"E15431-004"
CDS_SEC"1"
SEC_TYPE"0603V"
SEC"1"
CDS_LIB"dev_discrete"
CDS_LOCATION"C2G4";
"B"
$PN"2"13;
"A"
$PN"1"12;
%"CAP_A"
"1","(75,250)","0","dev_discrete","I282";
;
TOLERANCE"20%"
PART_NUMBER"602433-106"
GROUP"PWR_MLCC_CAP"
VOLTAGE"4V"
VALUE"47UF"
LOCATION"C2G5"
PACK_TYPE"0603V"
MATERIAL"X5R"
BOM_SS"E15431-004"
CDS_SEC"1"
SEC_TYPE"0603V"
SEC"1"
CDS_LIB"dev_discrete"
CDS_LOCATION"C2G5";
"B"
$PN"2"13;
"A"
$PN"1"12;
%"CAP_A"
"1","(375,250)","0","dev_discrete","I283";
;
GROUP"PWR_MLCC_CAP"
TOLERANCE"20%"
MATERIAL"X5R"
PACK_TYPE"0603V"
PART_NUMBER"602433-106"
VOLTAGE"4V"
VALUE"47UF"
LOCATION"C2G6"
BOM_SS"E15431-004"
CDS_SEC"1"
SEC_TYPE"0603V"
SEC"1"
CDS_LIB"dev_discrete"
CDS_LOCATION"C2G6";
"B"
$PN"2"13;
"A"
$PN"1"12;
%"CAP_A"
"1","(675,250)","0","dev_discrete","I284";
;
GROUP"PWR_MLCC_CAP"
VOLTAGE"4V"
VALUE"47UF"
TOLERANCE"20%"
LOCATION"C3G1"
MATERIAL"X5R"
PART_NUMBER"602433-106"
PACK_TYPE"0603V"
BOM_SS"E15431-004"
CDS_SEC"1"
SEC_TYPE"0603V"
SEC"1"
CDS_LIB"dev_discrete"
CDS_LOCATION"C3G1";
"B"
$PN"2"13;
"A"
$PN"1"12;
%"CAP_A"
"1","(950,250)","0","dev_discrete","I285";
;
PACK_TYPE"0603V"
PART_NUMBER"602433-106"
MATERIAL"X5R"
GROUP"PWR_MLCC_CAP"
LOCATION"C3G2"
TOLERANCE"20%"
VALUE"47UF"
VOLTAGE"4V"
BOM_SS"E15431-004"
CDS_LIB"dev_discrete"
SEC"1"
SEC_TYPE"0603V"
CDS_SEC"1"
CDS_LOCATION"C3G2";
"B"
$PN"2"13;
"A"
$PN"1"12;
%"CAP_A"
"1","(1225,250)","0","dev_discrete","I286";
;
LOCATION"C2G13"
VALUE"47UF"
GROUP"PWR_MLCC_CAP"
VOLTAGE"4V"
TOLERANCE"20%"
PACK_TYPE"0603V"
PART_NUMBER"602433-106"
MATERIAL"X5R"
BOM_SS"E15431-004"
CDS_SEC"1"
SEC_TYPE"0603V"
SEC"1"
CDS_LIB"dev_discrete"
CDS_LOCATION"C2G13";
"B"
$PN"2"13;
"A"
$PN"1"12;
%"CAP_A"
"1","(1525,250)","0","dev_discrete","I287";
;
GROUP"PWR_MLCC_CAP"
VOLTAGE"4V"
VALUE"47UF"
MATERIAL"X5R"
TOLERANCE"20%"
LOCATION"C2G14"
PACK_TYPE"0603V"
PART_NUMBER"602433-106"
BOM_SS"E15431-004"
CDS_SEC"1"
SEC_TYPE"0603V"
SEC"1"
CDS_LIB"dev_discrete"
CDS_LOCATION"C2G14";
"B"
$PN"2"13;
"A"
$PN"1"12;
%"CAP_A"
"1","(1825,250)","0","dev_discrete","I288";
;
VOLTAGE"4V"
VALUE"47UF"
LOCATION"C3G5"
TOLERANCE"20%"
GROUP"PWR_MLCC_CAP"
MATERIAL"X5R"
PACK_TYPE"0603V"
PART_NUMBER"602433-106"
BOM_SS"E15431-004"
CDS_SEC"1"
SEC_TYPE"0603V"
SEC"1"
CDS_LIB"dev_discrete"
CDS_LOCATION"C3G5";
"B"
$PN"2"13;
"A"
$PN"1"12;
%"CAP_A"
"1","(2100,250)","0","dev_discrete","I289";
;
LOCATION"C3G6"
PACK_TYPE"0603V"
PART_NUMBER"602433-106"
VALUE"47UF"
VOLTAGE"4V"
MATERIAL"X5R"
TOLERANCE"20%"
BOM_SS"E15431-004"
GROUP"PWR_MLCC_CAP"
CDS_SEC"1"
SEC_TYPE"0603V"
SEC"1"
CDS_LIB"dev_discrete"
CDS_LOCATION"C3G6";
"B"
$PN"2"13;
"A"
$PN"1"12;
%"CAP_A"
"1","(-2250,-450)","0","dev_discrete","I290";
;
GROUP"PWR_MLCC_CAP"
VALUE"47UF"
VOLTAGE"4V"
TOLERANCE"20%"
MATERIAL"X5R"
PACK_TYPE"0603V"
PART_NUMBER"602433-106"
LOCATION"C8U7"
BOM_SS"E15431-004"
CDS_LIB"dev_discrete"
SEC"1"
SEC_TYPE"0603V"
CDS_SEC"1"
CDS_LOCATION"C8U7";
"B"
$PN"2"15;
"A"
$PN"1"14;
%"CAP_A"
"1","(-1950,-450)","0","dev_discrete","I291";
;
GROUP"PWR_MLCC_CAP"
TOLERANCE"20%"
MATERIAL"X5R"
VOLTAGE"4V"
PART_NUMBER"602433-106"
PACK_TYPE"0603V"
LOCATION"C8U2"
VALUE"47UF"
BOM_SS"E15431-004"
CDS_SEC"1"
SEC_TYPE"0603V"
SEC"1"
CDS_LIB"dev_discrete"
CDS_LOCATION"C8U2";
"B"
$PN"2"15;
"A"
$PN"1"14;
%"CAP_A"
"1","(-1650,-450)","0","dev_discrete","I292";
;
GROUP"PWR_MLCC_CAP"
VALUE"47UF"
TOLERANCE"20%"
LOCATION"C7U2"
PACK_TYPE"0603V"
MATERIAL"X5R"
PART_NUMBER"602433-106"
VOLTAGE"4V"
BOM_SS"E15431-004"
CDS_SEC"1"
SEC_TYPE"0603V"
SEC"1"
CDS_LIB"dev_discrete"
CDS_LOCATION"C7U2";
"B"
$PN"2"15;
"A"
$PN"1"14;
%"CAP_A"
"1","(-1375,-450)","0","dev_discrete","I293";
;
GROUP"PWR_MLCC_CAP"
LOCATION"C7U1"
TOLERANCE"20%"
PACK_TYPE"0603V"
PART_NUMBER"602433-106"
MATERIAL"X5R"
VALUE"47UF"
VOLTAGE"4V"
BOM_SS"E15431-004"
CDS_LIB"dev_discrete"
SEC"1"
SEC_TYPE"0603V"
CDS_SEC"1"
CDS_LOCATION"C7U1";
"B"
$PN"2"15;
"A"
$PN"1"14;
%"CAP_A"
"1","(-1100,-450)","0","dev_discrete","I294";
;
GROUP"PWR_MLCC_CAP"
PACK_TYPE"0603V"
MATERIAL"X5R"
TOLERANCE"20%"
LOCATION"C8U3"
PART_NUMBER"602433-106"
VALUE"47UF"
VOLTAGE"4V"
BOM_SS"E15431-004"
CDS_SEC"1"
SEC_TYPE"0603V"
SEC"1"
CDS_LIB"dev_discrete"
CDS_LOCATION"C8U3";
"B"
$PN"2"15;
"A"
$PN"1"14;
%"CAP_A"
"1","(-800,-450)","0","dev_discrete","I295";
;
GROUP"PWR_MLCC_CAP"
LOCATION"C7T4"
TOLERANCE"20%"
MATERIAL"X5R"
PACK_TYPE"0603V"
PART_NUMBER"602433-106"
VOLTAGE"4V"
VALUE"47UF"
BOM_SS"E15431-004"
CDS_LIB"dev_discrete"
SEC"1"
SEC_TYPE"0603V"
CDS_SEC"1"
CDS_LOCATION"C7T4";
"B"
$PN"2"15;
"A"
$PN"1"14;
%"CAP_A"
"1","(-500,-450)","0","dev_discrete","I296";
;
GROUP"PWR_MLCC_CAP"
LOCATION"C7T5"
VOLTAGE"4V"
PART_NUMBER"602433-106"
PACK_TYPE"0603V"
MATERIAL"X5R"
TOLERANCE"20%"
VALUE"47UF"
BOM_SS"E15431-004"
CDS_SEC"1"
SEC_TYPE"0603V"
SEC"1"
CDS_LIB"dev_discrete"
CDS_LOCATION"C7T5";
"B"
$PN"2"15;
"A"
$PN"1"14;
%"CAP_A"
"1","(-225,-450)","0","dev_discrete","I297";
;
GROUP"PWR_MLCC_CAP"
LOCATION"C8T5"
TOLERANCE"20%"
MATERIAL"X5R"
PACK_TYPE"0603V"
PART_NUMBER"602433-106"
VOLTAGE"4V"
VALUE"47UF"
BOM_SS"E15431-004"
CDS_LIB"dev_discrete"
SEC"1"
SEC_TYPE"0603V"
CDS_SEC"1"
CDS_LOCATION"C8T5";
"B"
$PN"2"15;
"A"
$PN"1"14;
%"CAP_A"
"1","(100,-450)","0","dev_discrete","I298";
;
GROUP"PWR_MLCC_CAP"
VOLTAGE"4V"
PART_NUMBER"602433-106"
VALUE"47UF"
PACK_TYPE"0603V"
MATERIAL"X5R"
TOLERANCE"20%"
LOCATION"C8U6"
BOM_SS"E15431-004"
CDS_SEC"1"
SEC_TYPE"0603V"
SEC"1"
CDS_LIB"dev_discrete"
CDS_LOCATION"C8U6";
"B"
$PN"2"15;
"A"
$PN"1"14;
%"CAP_A"
"1","(400,-450)","0","dev_discrete","I299";
;
GROUP"PWR_MLCC_CAP"
LOCATION"C8T6"
TOLERANCE"20%"
MATERIAL"X5R"
PACK_TYPE"0603V"
VALUE"47UF"
PART_NUMBER"602433-106"
VOLTAGE"4V"
BOM_SS"E15431-004"
CDS_LIB"dev_discrete"
SEC"1"
SEC_TYPE"0603V"
CDS_SEC"1"
CDS_LOCATION"C8T6";
"B"
$PN"2"15;
"A"
$PN"1"14;
%"CAP_A"
"1","(700,-450)","0","dev_discrete","I300";
;
GROUP"PWR_MLCC_CAP"
LOCATION"C8T7"
VOLTAGE"4V"
PART_NUMBER"602433-106"
VALUE"47UF"
PACK_TYPE"0603V"
MATERIAL"X5R"
TOLERANCE"20%"
BOM_SS"E15431-004"
CDS_SEC"1"
SEC_TYPE"0603V"
SEC"1"
CDS_LIB"dev_discrete"
CDS_LOCATION"C8T7";
"B"
$PN"2"15;
"A"
$PN"1"14;
%"CAP_A"
"1","(975,-450)","0","dev_discrete","I301";
;
GROUP"PWR_MLCC_CAP"
LOCATION"C8T8"
TOLERANCE"20%"
MATERIAL"X5R"
PACK_TYPE"0603V"
VALUE"47UF"
PART_NUMBER"602433-106"
VOLTAGE"4V"
BOM_SS"E15431-004"
CDS_LIB"dev_discrete"
SEC"1"
SEC_TYPE"0603V"
CDS_SEC"1"
CDS_LOCATION"C8T8";
"B"
$PN"2"15;
"A"
$PN"1"14;
%"CAP_A"
"1","(1250,-450)","0","dev_discrete","I302";
;
VOLTAGE"4V"
PART_NUMBER"602433-106"
VALUE"47UF"
PACK_TYPE"0603V"
MATERIAL"X5R"
TOLERANCE"20%"
LOCATION"C8U5"
GROUP"PWR_MLCC_CAP"
BOM_SS"E15431-004"
CDS_SEC"1"
SEC_TYPE"0603V"
SEC"1"
CDS_LIB"dev_discrete"
CDS_LOCATION"C8U5";
"B"
$PN"2"15;
"A"
$PN"1"14;
%"CAP_A"
"1","(1550,-450)","0","dev_discrete","I303";
;
GROUP"PWR_MLCC_CAP"
LOCATION"C8T9"
VALUE"47UF"
VOLTAGE"4V"
PACK_TYPE"0603V"
PART_NUMBER"602433-106"
MATERIAL"X5R"
TOLERANCE"20%"
BOM_SS"E15431-004"
CDS_LIB"dev_discrete"
SEC"1"
SEC_TYPE"0603V"
CDS_SEC"1"
CDS_LOCATION"C8T9";
"B"
$PN"2"15;
"A"
$PN"1"14;
%"CAP_A"
"1","(1850,-450)","0","dev_discrete","I304";
;
LOCATION"C8T10"
VOLTAGE"4V"
VALUE"47UF"
MATERIAL"X5R"
TOLERANCE"20%"
PART_NUMBER"602433-106"
PACK_TYPE"0603V"
BOM_SS"E15431-004"
GROUP"PWR_MLCC_CAP"
CDS_SEC"1"
SEC_TYPE"0603V"
SEC"1"
CDS_LIB"dev_discrete"
CDS_LOCATION"C8T10";
"B"
$PN"2"15;
"A"
$PN"1"14;
%"CAP_A"
"1","(2125,-450)","0","dev_discrete","I305";
;
GROUP"PWR_MLCC_CAP"
VOLTAGE"4V"
VALUE"47UF"
MATERIAL"X5R"
TOLERANCE"20%"
LOCATION"C8U4"
PART_NUMBER"602433-106"
PACK_TYPE"0603V"
BOM_SS"E15431-004"
CDS_SEC"1"
SEC_TYPE"0603V"
SEC"1"
CDS_LIB"dev_discrete"
CDS_LOCATION"C8U4";
"B"
$PN"2"15;
"A"
$PN"1"14;
%"CAP"
"1","(3850,2825)","0","mstr_discrete","I307";
;
VALUE"100UF"
VOLTAGE"4V"
LOCATION"C8U11"
PACK_TYPE"0805"
TOLERANCE"20%"
NEW_MATERIAL"X6S"
GROUP"PWR_MLCC_CAP"
PART_NUMBER"602433-112"
BOM_SS"NOPOP"
NEW_PN"078.1071T.M002"
MATERIAL"X5R"
SEC"1"
SEC_TYPE"0805"
ROOM"VDDQ_ABC_PWR_VR"
BOM_COST"MEM_VRD_PVDDQ_CD"
CDS_LIB"mstr_discrete"
CDS_SEC"1"
CDS_LOCATION"C8U11";
"A"
$PN"1"26;
"B"
$PN"2"27;
%"CAP"
"1","(3150,2825)","0","mstr_discrete","I308";
;
LOCATION"C7U7"
NEW_MATERIAL"X6S"
GROUP"PWR_MLCC_CAP"
VOLTAGE"4V"
TOLERANCE"20%"
BOM_SS"NOPOP"
PART_NUMBER"602433-112"
PACK_TYPE"0805"
VALUE"100UF"
NEW_PN"078.1071T.M002"
CDS_SEC"1"
CDS_LIB"mstr_discrete"
BOM_COST"MEM_VRD_PVDDQ_CD"
ROOM"VDDQ_ABC_PWR_VR"
SEC_TYPE"0805"
SEC"1"
MATERIAL"X5R"
CDS_LOCATION"C7U7";
"A"
$PN"1"26;
"B"
$PN"2"27;
%"CAP"
"1","(3500,2825)","0","mstr_discrete","I309";
;
NEW_MATERIAL"X6S"
BOM_SS"NOPOP"
VALUE"100UF"
LOCATION"C7T1"
PACK_TYPE"0805"
GROUP"PWR_MLCC_CAP"
TOLERANCE"20%"
VOLTAGE"4V"
PART_NUMBER"602433-112"
NEW_PN"078.1071T.M002"
MATERIAL"X5R"
SEC"1"
SEC_TYPE"0805"
ROOM"VDDQ_ABC_PWR_VR"
BOM_COST"MEM_VRD_PVDDQ_CD"
CDS_LIB"mstr_discrete"
CDS_SEC"1"
CDS_LOCATION"C7T1";
"A"
$PN"1"26;
"B"
$PN"2"27;
%"CAP"
"1","(4250,2825)","0","mstr_discrete","I310";
;
BOM_SS"NOPOP"
NEW_MATERIAL"X6S"
PACK_TYPE"0805"
PART_NUMBER"602433-112"
VALUE"100UF"
VOLTAGE"4V"
TOLERANCE"20%"
LOCATION"C8U12"
GROUP"PWR_MLCC_CAP"
NEW_PN"078.1071T.M002"
MATERIAL"X5R"
SEC"1"
SEC_TYPE"0805"
ROOM"VDDQ_ABC_PWR_VR"
BOM_COST"MEM_VRD_PVDDQ_CD"
CDS_LIB"mstr_discrete"
CDS_SEC"1"
CDS_LOCATION"C8U12";
"A"
$PN"1"26;
"B"
$PN"2"27;
%"CAP"
"1","(2400,2825)","0","mstr_discrete","I311";
;
BOM_SS"NOPOP"
NEW_MATERIAL"X6S"
VALUE"100UF"
GROUP"PWR_MLCC_CAP"
PART_NUMBER"602433-112"
TOLERANCE"20%"
PACK_TYPE"0805"
VOLTAGE"4V"
LOCATION"C2G16"
NEW_PN"078.1071T.M002"
MATERIAL"X5R"
SEC"1"
SEC_TYPE"0805"
ROOM"VDDQ_ABC_PWR_VR"
BOM_COST"MEM_VRD_PVDDQ_CD"
CDS_LIB"mstr_discrete"
CDS_SEC"1"
CDS_LOCATION"C2G16";
"A"
$PN"1"26;
"B"
$PN"2"27;
%"CAP"
"1","(2750,2825)","0","mstr_discrete","I312";
;
PART_NUMBER"602433-112"
BOM_SS"NOPOP"
TOLERANCE"20%"
VOLTAGE"4V"
VALUE"100UF"
LOCATION"C2G7"
NEW_MATERIAL"X6S"
PACK_TYPE"0805"
GROUP"PWR_MLCC_CAP"
NEW_PN"078.1071T.M002"
MATERIAL"X5R"
SEC"1"
SEC_TYPE"0805"
ROOM"VDDQ_ABC_PWR_VR"
BOM_COST"MEM_VRD_PVDDQ_CD"
CDS_LIB"mstr_discrete"
CDS_SEC"1"
CDS_LOCATION"C2G7";
"A"
$PN"1"26;
"B"
$PN"2"27;
%"CAP"
"1","(-2325,3100)","0","mstr_discrete","I313";
;
VALUE"100UF"
LOCATION"C8P30"
TOLERANCE"20%"
VOLTAGE"4V"
PART_NUMBER"602433-112"
PACK_TYPE"0805"
BOM_SS"NOPOP"
GROUP"PWR_MLCC_CAP"
NEW_MATERIAL"X6S"
NEW_PN"078.1071T.M002"
CDS_SEC"1"
CDS_LIB"mstr_discrete"
BOM_COST"MEM_VRD_PVDDQ_CD"
ROOM"VDDQ_ABC_PWR_VR"
SEC_TYPE"0805"
SEC"1"
MATERIAL"X5R"
CDS_LOCATION"C8P30";
"A"
$PN"1"8;
"B"
$PN"2"1;
%"CAP"
"1","(-1975,3100)","0","mstr_discrete","I314";
;
PACK_TYPE"0805"
LOCATION"C8P31"
VALUE"100UF"
VOLTAGE"4V"
TOLERANCE"20%"
PART_NUMBER"602433-112"
BOM_SS"NOPOP"
GROUP"PWR_MLCC_CAP"
NEW_MATERIAL"X6S"
NEW_PN"078.1071T.M002"
CDS_SEC"1"
CDS_LIB"mstr_discrete"
BOM_COST"MEM_VRD_PVDDQ_CD"
ROOM"VDDQ_ABC_PWR_VR"
SEC_TYPE"0805"
SEC"1"
MATERIAL"X5R"
CDS_LOCATION"C8P31";
"A"
$PN"1"8;
"B"
$PN"2"1;
%"CAP"
"1","(100,3025)","0","mstr_discrete","I315";
;
NEW_PN"078.1071T.M002"
NEW_MATERIAL"X6S"
GROUP"PWR_MLCC_CAP"
PACK_TYPE"0805"
PART_NUMBER"602433-112"
VALUE"100UF"
VOLTAGE"4V"
TOLERANCE"20%"
LOCATION"C8P34"
BOM_SS"NOPOP"
MATERIAL"X5R"
SEC"1"
SEC_TYPE"0805"
ROOM"VDDQ_ABC_PWR_VR"
BOM_COST"MEM_VRD_PVDDQ_CD"
CDS_LIB"mstr_discrete"
CDS_SEC"1"
CDS_LOCATION"C8P34";
"A"
$PN"1"16;
"B"
$PN"2"17;
%"CAP"
"1","(450,3025)","0","mstr_discrete","I316";
;
GROUP"PWR_MLCC_CAP"
LOCATION"C8P33"
TOLERANCE"20%"
PACK_TYPE"0805"
VALUE"100UF"
NEW_MATERIAL"X6S"
PART_NUMBER"602433-112"
BOM_SS"NOPOP"
NEW_PN"078.1071T.M002"
VOLTAGE"4V"
CDS_SEC"1"
CDS_LIB"mstr_discrete"
BOM_COST"MEM_VRD_PVDDQ_CD"
ROOM"VDDQ_ABC_PWR_VR"
SEC_TYPE"0805"
SEC"1"
MATERIAL"X5R"
CDS_LOCATION"C8P33";
"A"
$PN"1"16;
"B"
$PN"2"17;
%"CAP"
"1","(800,3025)","0","mstr_discrete","I317";
;
VALUE"100UF"
TOLERANCE"20%"
PART_NUMBER"602433-112"
PACK_TYPE"0805"
VOLTAGE"4V"
NEW_MATERIAL"X6S"
GROUP"PWR_MLCC_CAP"
BOM_SS"NOPOP"
NEW_PN"078.1071T.M002"
LOCATION"C8P32"
MATERIAL"X5R"
SEC"1"
SEC_TYPE"0805"
ROOM"VDDQ_ABC_PWR_VR"
BOM_COST"MEM_VRD_PVDDQ_CD"
CDS_LIB"mstr_discrete"
CDS_SEC"1"
CDS_LOCATION"C8P32";
"A"
$PN"1"16;
"B"
$PN"2"17;
%"CAP"
"1","(1625,3050)","0","mstr_discrete","I318";
;
PART_NUMBER"602433-112"
TOLERANCE"20%"
VOLTAGE"4V"
PACK_TYPE"0805"
GROUP"PWR_MLCC_CAP"
BOM_SS"NOPOP"
LOCATION"C7P20"
VALUE"100UF"
NEW_MATERIAL"X6S"
NEW_PN"078.1071T.M002"
MATERIAL"X5R"
SEC"1"
SEC_TYPE"0805"
ROOM"VDDQ_ABC_PWR_VR"
BOM_COST"MEM_VRD_PVDDQ_CD"
CDS_LIB"mstr_discrete"
CDS_SEC"1"
CDS_LOCATION"C7P20";
"A"
$PN"1"21;
"B"
$PN"2"20;
%"CAP"
"1","(5000,2825)","0","mstr_discrete","I319";
;
BOM_SS"NOPOP"
VALUE"100UF"
LOCATION"C8U1"
PART_NUMBER"602433-112"
NEW_MATERIAL"X6S"
GROUP"PWR_MLCC_CAP"
TOLERANCE"20%"
VOLTAGE"4V"
PACK_TYPE"0805"
NEW_PN"078.1071T.M002"
CDS_SEC"1"
CDS_LIB"mstr_discrete"
BOM_COST"MEM_VRD_PVDDQ_CD"
ROOM"VDDQ_ABC_PWR_VR"
SEC_TYPE"0805"
SEC"1"
MATERIAL"X5R"
CDS_LOCATION"C8U1";
"A"
$PN"1"26;
"B"
$PN"2"27;
%"CAP"
"1","(4600,2825)","0","mstr_discrete","I320";
;
BOM_SS"NOPOP"
GROUP"PWR_MLCC_CAP"
NEW_MATERIAL"X6S"
PART_NUMBER"602433-112"
PACK_TYPE"0805"
TOLERANCE"20%"
LOCATION"C8U8"
VOLTAGE"4V"
VALUE"100UF"
NEW_PN"078.1071T.M002"
CDS_SEC"1"
CDS_LIB"mstr_discrete"
BOM_COST"MEM_VRD_PVDDQ_CD"
ROOM"VDDQ_ABC_PWR_VR"
SEC_TYPE"0805"
SEC"1"
MATERIAL"X5R"
CDS_LOCATION"C8U8";
"A"
$PN"1"26;
"B"
$PN"2"27;
%"ST270U2D5VBM-GP"
"1","(-1250,1150)","0","w_hdl","I327";
;
CDS_SEC"1"
CDS_LOCATION"C1G15"
NEW_VALUE"33UF"
NEW_SIZE"B2"
LOCATION"C1G15"
NEW_PN"077.C3361.0001"
CDS_LMAN_SYM_OUTLINE"-50,25,50,-25"
CDS_LIB"w_hdl"
PART_NUMBER"077.C2771.0001"
SEC_TYPE"SMD-TCG2"
SEC"1"
PACK_TYPE"SMD-TCG2"
VALUE"ST270U2D5VBM-GP";
"2"
$PN"2"5;
"1"
$PN"1"4;
%"ST270U2D5VBM-GP"
"1","(-550,1150)","0","w_hdl","I328";
;
CDS_SEC"1"
CDS_LOCATION"C1G12"
NEW_PN"077.C3361.0001"
NEW_SIZE"B2"
NEW_VALUE"33UF"
LOCATION"C1G12"
PART_NUMBER"077.C2771.0001"
PACK_TYPE"SMD-TCG2"
VALUE"ST270U2D5VBM-GP"
SEC_TYPE"SMD-TCG2"
SEC"1"
CDS_LMAN_SYM_OUTLINE"-50,25,50,-25"
CDS_LIB"w_hdl";
"2"
$PN"2"5;
"1"
$PN"1"4;
%"ST270U2D5VBM-GP"
"1","(850,1150)","0","w_hdl","I329";
;
CDS_SEC"1"
CDS_LOCATION"C1G7"
LOCATION"C1G7"
NEW_PN"077.C3361.0001"
NEW_VALUE"33UF"
NEW_SIZE"B2"
SEC_TYPE"SMD-TCG2"
SEC"1"
PACK_TYPE"SMD-TCG2"
CDS_LIB"w_hdl"
CDS_LMAN_SYM_OUTLINE"-50,25,50,-25"
PART_NUMBER"077.C2771.0001"
VALUE"ST270U2D5VBM-GP";
"2"
$PN"2"5;
"1"
$PN"1"4;
%"RES"
"2","(4450,-25)","0","mstr_discrete","I58";
;
LOCATION"R1G20"
MATERIAL"CHIP"
WATTAGE"1/10W"
PACK_TYPE"0603"
PART_NUMBER"G22026-003"
TOLERANCE"1%"
VALUE"120.0"
CDS_LIB"mstr_discrete"
BOM_COST"MEM_VRD_PVPP_AB"
CDS_SEC"1"
$SEC"1"
CDS_LOCATION"R1G20"
ROOM"VDDQ_GHJ_PWR_VR";
"A"
$PN"1"24;
"B"
$PN"2"25;
%"GND"
"1","(100,1750)","0","mstr_symbols","I65";
;
ROOM"VDDQ_GHJ_PWR_VR"
BOM_COST"MEM_VRD_PVPP_AB"
VOLTAGE"0"
CDS_LIB"mstr_symbols"
SIZE"1B"
BODY_TYPE"PLUMBING"
HDL_POWER"GND";
"A\NAC"22;
%"PVDDQ_GHJ"
"1","(100,2450)","0","mstr_symbols","I73";
;
VOLTAGE"1.2V"
CDS_LIB"mstr_symbols"
BOM_COST"MEM_VRD_PVPP_AB"
ROOM"VDDQ_GHJ_PWR_VR"
BODY_TYPE"PLUMBING"
HDL_POWER"PVDDQ_GHJ";
"G\NAC"23;
%"RES"
"2","(-650,2075)","0","mstr_discrete","I74";
;
CDS_SEC"1"
MATERIAL"EMPTY"
TOLERANCE"1%"
WATTAGE"1/16W"
LOCATION"R7U2"
VALUE"100.0"
PART_NUMBER"G21796-017"
PACK_TYPE"0402"
CDS_LIB"mstr_discrete"
CDS_LOCATION"R7U2"
ROOM"VDDQ_GHJ_PWR_VR"
SEC_TYPE"0402"
SEC"1";
"A"
$PN"1"28;
"B"
$PN"2"29;
%"CAPP"
"1","(3250,-50)","0","mstr_discrete","I75";
;
CDS_SEC"1"
PART_NUMBER"699013-049"
GROUP"PWR_BULK_CAP"
LOCATION"C9T5"
VALUE"470UF"
MATERIAL"ALUM"
PACK_TYPE"3018"
VOLTAGE"2.5V"
TOLERANCE"20%"
SEC_TYPE"3018"
SEC"1"
ROOM"VDDQ_GHJ_PWR_VR"
CDS_LOCATION"C9T5"
CDS_LIB"mstr_discrete";
"B"
$PN"2"25;
"A"
$PN"1"24;
%"CAPP"
"1","(3550,-50)","0","mstr_discrete","I76";
;
CDS_SEC"1"
LOCATION"C9U2"
GROUP"PWR_BULK_CAP"
VOLTAGE"2.5V"
MATERIAL"ALUM"
PART_NUMBER"699013-049"
PACK_TYPE"3018"
TOLERANCE"20%"
VALUE"470UF"
SEC_TYPE"3018"
SEC"1"
CDS_LOCATION"C9U2"
ROOM"VDDQ_GHJ_PWR_VR"
CDS_LIB"mstr_discrete";
"B"
$PN"2"25;
"A"
$PN"1"24;
%"CAPP"
"1","(3850,-50)","0","mstr_discrete","I77";
;
CDS_SEC"1"
VALUE"470UF"
GROUP"PWR_BULK_CAP"
LOCATION"C9U9"
PART_NUMBER"699013-049"
PACK_TYPE"3018"
MATERIAL"ALUM"
TOLERANCE"20%"
VOLTAGE"2.5V"
CDS_LIB"mstr_discrete"
SEC_TYPE"3018"
SEC"1"
CDS_LOCATION"C9U9"
ROOM"VDDQ_GHJ_PWR_VR";
"B"
$PN"2"25;
"A"
$PN"1"24;
%"CAPP"
"1","(4150,-50)","0","mstr_discrete","I78";
;
CDS_SEC"1"
GROUP"PWR_BULK_CAP"
PART_NUMBER"699013-049"
PACK_TYPE"3018"
MATERIAL"ALUM"
VOLTAGE"2.5V"
TOLERANCE"20%"
LOCATION"C9U5"
VALUE"470UF"
CDS_LIB"mstr_discrete"
CDS_LOCATION"C9U5"
SEC_TYPE"3018"
SEC"1"
ROOM"VDDQ_GHJ_PWR_VR";
"B"
$PN"2"25;
"A"
$PN"1"24;
%"PVDDQ_GHJ"
"1","(3250,250)","0","mstr_symbols","I80";
;
ROOM"VDDQ_GHJ_PWR_VR"
BOM_COST"MEM_VRD_PVPP_AB"
CDS_LIB"mstr_symbols"
VOLTAGE"1.2V"
BODY_TYPE"PLUMBING"
HDL_POWER"PVDDQ_GHJ";
"G\NAC"24;
%"GND"
"1","(3250,-375)","0","mstr_symbols","I81";
;
BOM_COST"MEM_VRD_PVPP_AB"
SIZE"1B"
CDS_LIB"mstr_symbols"
VOLTAGE"0"
BODY_TYPE"PLUMBING"
HDL_POWER"GND";
"A\NAC"25;
%"PVDDQ_GHJ"
"1","(2400,3100)","0","mstr_symbols","I93";
;
VOLTAGE"1.2V"
BOM_COST"MEM_VRD_PVDDQ_CD"
CDS_LIB"mstr_symbols"
ROOM"VDDQ_GHJ_PWR_VR"
BODY_TYPE"PLUMBING"
HDL_POWER"PVDDQ_GHJ";
"G\NAC"26;
%"GND"
"1","(2400,2350)","0","mstr_symbols","I94";
;
SIZE"1B"
CDS_LIB"mstr_symbols"
VOLTAGE"0"
BOM_COST"MEM_VRD_PVDDQ_CD"
ROOM"VDDQ_GHJ_PWR_VR"
BODY_TYPE"PLUMBING"
HDL_POWER"GND";
"A\NAC"27;
END.
